# BARRELEYE_G2-FPDB_POST-EVT-HW-EBOM-X00_20161123-add_2nd_source_X08-20161215-Final-b.xls — TLA-POST (bom)
| FOXCONN TECHNOLOGY GROUP |  |  |  |  |  |  |  |  |  |
| BILL OF MATERIAL |  |  |  |  |  |  |  |  |  |
| AA P/N | 1A42GQG00-600-G | CUSTOMER | <name> | Customer P/N |  | Product Code |  |  |  |
| PWA P/N |  | PWA DESCRIPTION | 風扇及電源分配板,ASSY,POST BOARD,G,BARRELEYE G2,RACKSPACE |  |  | PWA REV |  | Prepared By SE |  |
| Item | FOXCONN P/N | Customer P/N | Part Description | Manufacturer  Full Name | Manufacturer  Part Number | Qty | RoHS Status | Location | Remark |
| 1 | 7J-004-938 |  | L6 LABEL ( 12.7*11.1mm) | FOXCONN / EPD1 | 7J-004-938 | 1 | G |  | ID label for two boards. Post card AA P/N: 1A42GQG00-600-G |
